(kicad_pcb
	(version 20241229)
	(generator "pcbnew")
	(generator_version "9.0")
	(general
		(thickness 1.294)
		(legacy_teardrops no)
	)
	(paper "A3")
	(title_block
		(title "Kintex 410T devboard")
		(date "2024-04-03")
		(rev "1.1.2")
		(comment 9 "footprint 89 of 975 (J18), pads 183-270 of 564")
	)
	(layers
		(0 "F.Cu" mixed)
		(4 "In1.Cu" power)
		(6 "In2.Cu" power)
		(8 "In3.Cu" mixed)
		(10 "In4.Cu" power)
		(12 "In5.Cu" mixed)
		(14 "In6.Cu" power)
		(16 "In7.Cu" mixed)
		(18 "In8.Cu" power)
		(2 "B.Cu" mixed)
		(9 "F.Adhes" user "F.Adhesive")
		(11 "B.Adhes" user "B.Adhesive")
		(13 "F.Paste" user)
		(15 "B.Paste" user)
		(5 "F.SilkS" user "F.Silkscreen")
		(7 "B.SilkS" user "B.Silkscreen")
		(1 "F.Mask" user)
		(3 "B.Mask" user)
		(17 "Dwgs.User" user "User.Drawings")
		(19 "Cmts.User" user "User.Comments")
		(21 "Eco1.User" user "User.Eco1")
		(23 "Eco2.User" user "User.Eco2")
		(25 "Edge.Cuts" user)
		(27 "Margin" user)
		(31 "F.CrtYd" user "F.Courtyard")
		(29 "B.CrtYd" user "B.Courtyard")
		(35 "F.Fab" user)
		(33 "B.Fab" user)
	)
	(footprint "antmicro-footprints:ASP-184329-01_mounting_holes"
		(layer "F.Cu")
		(at 162.000001 106.000001 90)
		(property "Reference" "J18"
			(at 28.280001 4.299999 180)
			(layer "F.SilkS")
			(effects
				(font
					(size 0.7 0.7)
					(thickness 0.15)
				)
				(justify left bottom)
			)
		)
		(property "Value" "ASP-184329-01_mounting_holes"
			(at -8.4 0.2 90)
			(layer "F.Fab")
			(effects
				(font
					(size 0.7 0.7)
					(thickness 0.15)
				)
				(justify left bottom)
			)
		)
		(property "Description" "Mezzanine Connector, Array, Female, 1.27 mm, 14 Rows, 560 Contacts, Surface Mount"
			(at 0 0 90)
			(layer "F.Fab")
			(hide yes)
			(effects
				(font
					(size 1.27 1.27)
					(thickness 0.15)
				)
			)
		)
		(property "Author" "Antmicro"
			(at 268.000002 -56 0)
			(layer "F.Fab")
			(hide yes)
			(effects
				(font
					(size 1 1)
					(thickness 0.15)
				)
			)
		)
		(property "License" "Apache-2.0"
			(at 268.000002 -56 0)
			(layer "F.Fab")
			(hide yes)
			(effects
				(font
					(size 1 1)
					(thickness 0.15)
				)
			)
		)
		(property "MPN" "ASP-184329-01"
			(at 268.000002 -56 0)
			(layer "F.Fab")
			(hide yes)
			(effects
				(font
					(size 1 1)
					(thickness 0.15)
				)
			)
		)
		(property "Manufacturer" "Samtec"
			(at 268.000002 -56 0)
			(layer "F.Fab")
			(hide yes)
			(effects
				(font
					(size 1 1)
					(thickness 0.15)
				)
			)
		)
		(sheetname "FMC+ HSPC")
		(sheetfile "fmc-hspc.kicad_sch")
		(attr smd)
		(pad "E19" smd circle
			(at 1.904 0.633 90)
			(size 0.64 0.64)
			(layers "F.Cu" "F.Mask")
			(net 138 "unconnected-(J18D-HA20_N-PadE19)")
			(pinfunction "HA20_N")
			(pintype "passive+no_connect")
		)
		(pad "E20" smd circle
			(at 0.633 0.633 90)
			(size 0.64 0.64)
			(layers "F.Cu" "F.Mask")
			(net 1 "GND")
			(pinfunction "GND")
			(pintype "passive")
		)
		(pad "E21" smd circle
			(at -0.635 0.633 90)
			(size 0.64 0.64)
			(layers "F.Cu" "F.Mask")
			(net 139 "unconnected-(J18E-HB03_P-PadE21)")
			(pinfunction "HB03_P")
			(pintype "passive+no_connect")
		)
		(pad "E22" smd circle
			(at -1.905 0.633 90)
			(size 0.64 0.64)
			(layers "F.Cu" "F.Mask")
			(net 140 "unconnected-(J18E-HB03_N-PadE22)")
			(pinfunction "HB03_N")
			(pintype "passive+no_connect")
		)
		(pad "E23" smd circle
			(at -3.176 0.633 90)
			(size 0.64 0.64)
			(layers "F.Cu" "F.Mask")
			(net 1 "GND")
			(pinfunction "GND")
			(pintype "passive")
		)
		(pad "E24" smd circle
			(at -4.446 0.633 90)
			(size 0.64 0.64)
			(layers "F.Cu" "F.Mask")
			(net 141 "unconnected-(J18E-HB05_P-PadE24)")
			(pinfunction "HB05_P")
			(pintype "passive+no_connect")
		)
		(pad "E25" smd circle
			(at -5.715 0.633 90)
			(size 0.64 0.64)
			(layers "F.Cu" "F.Mask")
			(net 142 "unconnected-(J18E-HB05_N-PadE25)")
			(pinfunction "HB05_N")
			(pintype "passive+no_connect")
		)
		(pad "E26" smd circle
			(at -6.986 0.633 90)
			(size 0.64 0.64)
			(layers "F.Cu" "F.Mask")
			(net 1 "GND")
			(pinfunction "GND")
			(pintype "passive")
		)
		(pad "E27" smd circle
			(at -8.257 0.633 90)
			(size 0.64 0.64)
			(layers "F.Cu" "F.Mask")
			(net 144 "unconnected-(J18E-HB09_P-PadE27)")
			(pinfunction "HB09_P")
			(pintype "passive+no_connect")
		)
		(pad "E28" smd circle
			(at -9.526 0.633 90)
			(size 0.64 0.64)
			(layers "F.Cu" "F.Mask")
			(net 145 "unconnected-(J18E-HB09_N-PadE28)")
			(pinfunction "HB09_N")
			(pintype "passive+no_connect")
		)
		(pad "E29" smd circle
			(at -10.795 0.633 90)
			(size 0.64 0.64)
			(layers "F.Cu" "F.Mask")
			(net 1 "GND")
			(pinfunction "GND")
			(pintype "passive")
		)
		(pad "E30" smd circle
			(at -12.065 0.633 90)
			(size 0.64 0.64)
			(layers "F.Cu" "F.Mask")
			(net 146 "unconnected-(J18E-HB13_P-PadE30)")
			(pinfunction "HB13_P")
			(pintype "passive+no_connect")
		)
		(pad "E31" smd circle
			(at -13.337 0.633 90)
			(size 0.64 0.64)
			(layers "F.Cu" "F.Mask")
			(net 147 "unconnected-(J18E-HB13_N-PadE31)")
			(pinfunction "HB13_N")
			(pintype "passive+no_connect")
		)
		(pad "E32" smd circle
			(at -14.606 0.633 90)
			(size 0.64 0.64)
			(layers "F.Cu" "F.Mask")
			(net 1 "GND")
			(pinfunction "GND")
			(pintype "passive")
		)
		(pad "E33" smd circle
			(at -15.875 0.633 90)
			(size 0.64 0.64)
			(layers "F.Cu" "F.Mask")
			(net 148 "unconnected-(J18E-HB19_P-PadE33)")
			(pinfunction "HB19_P")
			(pintype "passive+no_connect")
		)
		(pad "E34" smd circle
			(at -17.145 0.633 90)
			(size 0.64 0.64)
			(layers "F.Cu" "F.Mask")
			(net 149 "unconnected-(J18E-HB19_N-PadE34)")
			(pinfunction "HB19_N")
			(pintype "passive+no_connect")
		)
		(pad "E35" smd circle
			(at -18.415 0.633 90)
			(size 0.64 0.64)
			(layers "F.Cu" "F.Mask")
			(net 1 "GND")
			(pinfunction "GND")
			(pintype "passive")
		)
		(pad "E36" smd circle
			(at -19.685 0.633 90)
			(size 0.64 0.64)
			(layers "F.Cu" "F.Mask")
			(net 150 "unconnected-(J18E-HB21_P-PadE36)")
			(pinfunction "HB21_P")
			(pintype "passive+no_connect")
		)
		(pad "E37" smd circle
			(at -20.956 0.633 90)
			(size 0.64 0.64)
			(layers "F.Cu" "F.Mask")
			(net 151 "unconnected-(J18E-HB21_N-PadE37)")
			(pinfunction "HB21_N")
			(pintype "passive+no_connect")
		)
		(pad "E38" smd circle
			(at -22.226 0.633 90)
			(size 0.64 0.64)
			(layers "F.Cu" "F.Mask")
			(net 1 "GND")
			(pinfunction "GND")
			(pintype "passive")
		)
		(pad "E39" smd circle
			(at -23.497 0.633 90)
			(size 0.64 0.64)
			(layers "F.Cu" "F.Mask")
			(net 152 "unconnected-(J18A-VADJ-PadE39)")
			(pinfunction "VADJ")
			(pintype "passive+no_connect")
		)
		(pad "E40" smd circle
			(at -24.767 0.633 90)
			(size 0.64 0.64)
			(layers "F.Cu" "F.Mask")
			(net 1 "GND")
			(pinfunction "GND")
			(pintype "passive")
		)
		(pad "F01" smd circle
			(at 24.765 -0.635 90)
			(size 0.64 0.64)
			(layers "F.Cu" "F.Mask")
			(net 153 "Net-(J18B-PG_M2C)")
			(pinfunction "PG_M2C")
			(pintype "passive")
		)
		(pad "F02" smd circle
			(at 23.495 -0.635 90)
			(size 0.64 0.64)
			(layers "F.Cu" "F.Mask")
			(net 1 "GND")
			(pinfunction "GND")
			(pintype "passive")
		)
		(pad "F03" smd circle
			(at 22.225 -0.635 90)
			(size 0.64 0.64)
			(layers "F.Cu" "F.Mask")
			(net 1 "GND")
			(pinfunction "GND")
			(pintype "passive")
		)
		(pad "F04" smd circle
			(at 20.954 -0.635 90)
			(size 0.64 0.64)
			(layers "F.Cu" "F.Mask")
			(net 154 "unconnected-(J18D-HA00_P_CC-PadF04)")
			(pinfunction "HA00_P_CC")
			(pintype "passive+no_connect")
		)
		(pad "F05" smd circle
			(at 19.684 -0.635 90)
			(size 0.64 0.64)
			(layers "F.Cu" "F.Mask")
			(net 155 "unconnected-(J18D-HA00_N_CC-PadF05)")
			(pinfunction "HA00_N_CC")
			(pintype "passive+no_connect")
		)
		(pad "F06" smd circle
			(at 18.414 -0.635 90)
			(size 0.64 0.64)
			(layers "F.Cu" "F.Mask")
			(net 1 "GND")
			(pinfunction "GND")
			(pintype "passive")
		)
		(pad "F07" smd circle
			(at 17.144 -0.635 90)
			(size 0.64 0.64)
			(layers "F.Cu" "F.Mask")
			(net 156 "unconnected-(J18D-HA04_P-PadF07)")
			(pinfunction "HA04_P")
			(pintype "passive+no_connect")
		)
		(pad "F08" smd circle
			(at 15.874 -0.635 90)
			(size 0.64 0.64)
			(layers "F.Cu" "F.Mask")
			(net 157 "unconnected-(J18D-HA04_N-PadF08)")
			(pinfunction "HA04_N")
			(pintype "passive+no_connect")
		)
		(pad "F09" smd circle
			(at 14.605 -0.635 90)
			(size 0.64 0.64)
			(layers "F.Cu" "F.Mask")
			(net 1 "GND")
			(pinfunction "GND")
			(pintype "passive")
		)
		(pad "F10" smd circle
			(at 13.335 -0.635 90)
			(size 0.64 0.64)
			(layers "F.Cu" "F.Mask")
			(net 158 "unconnected-(J18D-HA08_P-PadF10)")
			(pinfunction "HA08_P")
			(pintype "passive+no_connect")
		)
		(pad "F11" smd circle
			(at 12.063 -0.635 90)
			(size 0.64 0.64)
			(layers "F.Cu" "F.Mask")
			(net 159 "unconnected-(J18D-HA08_N-PadF11)")
			(pinfunction "HA08_N")
			(pintype "passive+no_connect")
		)
		(pad "F12" smd circle
			(at 10.794 -0.635 90)
			(size 0.64 0.64)
			(layers "F.Cu" "F.Mask")
			(net 1 "GND")
			(pinfunction "GND")
			(pintype "passive")
		)
		(pad "F13" smd circle
			(at 9.525 -0.635 90)
			(size 0.64 0.64)
			(layers "F.Cu" "F.Mask")
			(net 160 "unconnected-(J18D-HA12_P-PadF13)")
			(pinfunction "HA12_P")
			(pintype "passive+no_connect")
		)
		(pad "F14" smd circle
			(at 8.255 -0.635 90)
			(size 0.64 0.64)
			(layers "F.Cu" "F.Mask")
			(net 162 "unconnected-(J18D-HA12_N-PadF14)")
			(pinfunction "HA12_N")
			(pintype "passive+no_connect")
		)
		(pad "F15" smd circle
			(at 6.985 -0.635 90)
			(size 0.64 0.64)
			(layers "F.Cu" "F.Mask")
			(net 1 "GND")
			(pinfunction "GND")
			(pintype "passive")
		)
		(pad "F16" smd circle
			(at 5.714 -0.635 90)
			(size 0.64 0.64)
			(layers "F.Cu" "F.Mask")
			(net 163 "unconnected-(J18D-HA15_P-PadF16)")
			(pinfunction "HA15_P")
			(pintype "passive+no_connect")
		)
		(pad "F17" smd circle
			(at 4.445 -0.635 90)
			(size 0.64 0.64)
			(layers "F.Cu" "F.Mask")
			(net 164 "unconnected-(J18D-HA15_N-PadF17)")
			(pinfunction "HA15_N")
			(pintype "passive+no_connect")
		)
		(pad "F18" smd circle
			(at 3.173 -0.635 90)
			(size 0.64 0.64)
			(layers "F.Cu" "F.Mask")
			(net 1 "GND")
			(pinfunction "GND")
			(pintype "passive")
		)
		(pad "F19" smd circle
			(at 1.904 -0.635 90)
			(size 0.64 0.64)
			(layers "F.Cu" "F.Mask")
			(net 166 "unconnected-(J18D-HA19_P-PadF19)")
			(pinfunction "HA19_P")
			(pintype "passive+no_connect")
		)
		(pad "F20" smd circle
			(at 0.633 -0.635 90)
			(size 0.64 0.64)
			(layers "F.Cu" "F.Mask")
			(net 167 "unconnected-(J18D-HA19_N-PadF20)")
			(pinfunction "HA19_N")
			(pintype "passive+no_connect")
		)
		(pad "F21" smd circle
			(at -0.635 -0.635 90)
			(size 0.64 0.64)
			(layers "F.Cu" "F.Mask")
			(net 1 "GND")
			(pinfunction "GND")
			(pintype "passive")
		)
		(pad "F22" smd circle
			(at -1.905 -0.635 90)
			(size 0.64 0.64)
			(layers "F.Cu" "F.Mask")
			(net 168 "unconnected-(J18E-HB02_P-PadF22)")
			(pinfunction "HB02_P")
			(pintype "passive+no_connect")
		)
		(pad "F23" smd circle
			(at -3.176 -0.635 90)
			(size 0.64 0.64)
			(layers "F.Cu" "F.Mask")
			(net 169 "unconnected-(J18E-HB02_N-PadF23)")
			(pinfunction "HB02_N")
			(pintype "passive+no_connect")
		)
		(pad "F24" smd circle
			(at -4.446 -0.635 90)
			(size 0.64 0.64)
			(layers "F.Cu" "F.Mask")
			(net 1 "GND")
			(pinfunction "GND")
			(pintype "passive")
		)
		(pad "F25" smd circle
			(at -5.715 -0.635 90)
			(size 0.64 0.64)
			(layers "F.Cu" "F.Mask")
			(net 170 "unconnected-(J18E-HB04_P-PadF25)")
			(pinfunction "HB04_P")
			(pintype "passive+no_connect")
		)
		(pad "F26" smd circle
			(at -6.986 -0.635 90)
			(size 0.64 0.64)
			(layers "F.Cu" "F.Mask")
			(net 171 "unconnected-(J18E-HB04_N-PadF26)")
			(pinfunction "HB04_N")
			(pintype "passive+no_connect")
		)
		(pad "F27" smd circle
			(at -8.257 -0.635 90)
			(size 0.64 0.64)
			(layers "F.Cu" "F.Mask")
			(net 1 "GND")
			(pinfunction "GND")
			(pintype "passive")
		)
		(pad "F28" smd circle
			(at -9.526 -0.635 90)
			(size 0.64 0.64)
			(layers "F.Cu" "F.Mask")
			(net 172 "unconnected-(J18E-HB08_P-PadF28)")
			(pinfunction "HB08_P")
			(pintype "passive+no_connect")
		)
		(pad "F29" smd circle
			(at -10.795 -0.635 90)
			(size 0.64 0.64)
			(layers "F.Cu" "F.Mask")
			(net 173 "unconnected-(J18E-HB08_N-PadF29)")
			(pinfunction "HB08_N")
			(pintype "passive+no_connect")
		)
		(pad "F30" smd circle
			(at -12.065 -0.635 90)
			(size 0.64 0.64)
			(layers "F.Cu" "F.Mask")
			(net 1 "GND")
			(pinfunction "GND")
			(pintype "passive")
		)
		(pad "F31" smd circle
			(at -13.337 -0.635 90)
			(size 0.64 0.64)
			(layers "F.Cu" "F.Mask")
			(net 174 "unconnected-(J18E-HB12_P-PadF31)")
			(pinfunction "HB12_P")
			(pintype "passive+no_connect")
		)
		(pad "F32" smd circle
			(at -14.606 -0.635 90)
			(size 0.64 0.64)
			(layers "F.Cu" "F.Mask")
			(net 175 "unconnected-(J18E-HB12_N-PadF32)")
			(pinfunction "HB12_N")
			(pintype "passive+no_connect")
		)
		(pad "F33" smd circle
			(at -15.875 -0.635 90)
			(size 0.64 0.64)
			(layers "F.Cu" "F.Mask")
			(net 1 "GND")
			(pinfunction "GND")
			(pintype "passive")
		)
		(pad "F34" smd circle
			(at -17.145 -0.635 90)
			(size 0.64 0.64)
			(layers "F.Cu" "F.Mask")
			(net 176 "unconnected-(J18E-HB16_P-PadF34)")
			(pinfunction "HB16_P")
			(pintype "passive+no_connect")
		)
		(pad "F35" smd circle
			(at -18.415 -0.635 90)
			(size 0.64 0.64)
			(layers "F.Cu" "F.Mask")
			(net 177 "unconnected-(J18E-HB16_N-PadF35)")
			(pinfunction "HB16_N")
			(pintype "passive+no_connect")
		)
		(pad "F36" smd circle
			(at -19.685 -0.635 90)
			(size 0.64 0.64)
			(layers "F.Cu" "F.Mask")
			(net 1 "GND")
			(pinfunction "GND")
			(pintype "passive")
		)
		(pad "F37" smd circle
			(at -20.956 -0.635 90)
			(size 0.64 0.64)
			(layers "F.Cu" "F.Mask")
			(net 178 "unconnected-(J18E-HB20_P-PadF37)")
			(pinfunction "HB20_P")
			(pintype "passive+no_connect")
		)
		(pad "F38" smd circle
			(at -22.226 -0.635 90)
			(size 0.64 0.64)
			(layers "F.Cu" "F.Mask")
			(net 179 "unconnected-(J18E-HB20_N-PadF38)")
			(pinfunction "HB20_N")
			(pintype "passive+no_connect")
		)
		(pad "F39" smd circle
			(at -23.497 -0.635 90)
			(size 0.64 0.64)
			(layers "F.Cu" "F.Mask")
			(net 1 "GND")
			(pinfunction "GND")
			(pintype "passive")
		)
		(pad "F40" smd circle
			(at -24.767 -0.635 90)
			(size 0.64 0.64)
			(layers "F.Cu" "F.Mask")
			(net 152 "unconnected-(J18A-VADJ-PadE39)")
			(pinfunction "VADJ")
			(pintype "passive+no_connect")
		)
		(pad "G01" smd circle
			(at 24.765 -1.905 90)
			(size 0.64 0.64)
			(layers "F.Cu" "F.Mask")
			(net 1 "GND")
			(pinfunction "GND")
			(pintype "passive")
		)
		(pad "G02" smd circle
			(at 23.495 -1.905 90)
			(size 0.64 0.64)
			(layers "F.Cu" "F.Mask")
			(net 180 "unconnected-(J18F-CLK1_M2C_P-PadG02)")
			(pinfunction "CLK1_M2C_P")
			(pintype "passive+no_connect")
		)
		(pad "G03" smd circle
			(at 22.225 -1.905 90)
			(size 0.64 0.64)
			(layers "F.Cu" "F.Mask")
			(net 181 "unconnected-(J18F-CLK1_M2C_N-PadG03)")
			(pinfunction "CLK1_M2C_N")
			(pintype "passive+no_connect")
		)
		(pad "G04" smd circle
			(at 20.954 -1.905 90)
			(size 0.64 0.64)
			(layers "F.Cu" "F.Mask")
			(net 1 "GND")
			(pinfunction "GND")
			(pintype "passive")
		)
		(pad "G05" smd circle
			(at 19.684 -1.905 90)
			(size 0.64 0.64)
			(layers "F.Cu" "F.Mask")
			(net 1 "GND")
			(pinfunction "GND")
			(pintype "passive")
		)
		(pad "G06" smd circle
			(at 18.414 -1.905 90)
			(size 0.64 0.64)
			(layers "F.Cu" "F.Mask")
			(net 182 "unconnected-(J18C-LA00_P_CC-PadG06)")
			(pinfunction "LA00_P_CC")
			(pintype "passive+no_connect")
		)
		(pad "G07" smd circle
			(at 17.144 -1.905 90)
			(size 0.64 0.64)
			(layers "F.Cu" "F.Mask")
			(net 183 "unconnected-(J18C-LA00_N_CC-PadG07)")
			(pinfunction "LA00_N_CC")
			(pintype "passive+no_connect")
		)
		(pad "G08" smd circle
			(at 15.874 -1.905 90)
			(size 0.64 0.64)
			(layers "F.Cu" "F.Mask")
			(net 1 "GND")
			(pinfunction "GND")
			(pintype "passive")
		)
		(pad "G09" smd circle
			(at 14.605 -1.905 90)
			(size 0.64 0.64)
			(layers "F.Cu" "F.Mask")
			(net 184 "unconnected-(J18C-LA03_P-PadG09)")
			(pinfunction "LA03_P")
			(pintype "passive+no_connect")
		)
		(pad "G10" smd circle
			(at 13.335 -1.905 90)
			(size 0.64 0.64)
			(layers "F.Cu" "F.Mask")
			(net 185 "unconnected-(J18C-LA03_N-PadG10)")
			(pinfunction "LA03_N")
			(pintype "passive+no_connect")
		)
		(pad "G11" smd circle
			(at 12.063 -1.905 90)
			(size 0.64 0.64)
			(layers "F.Cu" "F.Mask")
			(net 1 "GND")
			(pinfunction "GND")
			(pintype "passive")
		)
		(pad "G12" smd circle
			(at 10.794 -1.905 90)
			(size 0.64 0.64)
			(layers "F.Cu" "F.Mask")
			(net 186 "unconnected-(J18C-LA08_P-PadG12)")
			(pinfunction "LA08_P")
			(pintype "passive+no_connect")
		)
		(pad "G13" smd circle
			(at 9.525 -1.905 90)
			(size 0.64 0.64)
			(layers "F.Cu" "F.Mask")
			(net 187 "unconnected-(J18C-LA08_N-PadG13)")
			(pinfunction "LA08_N")
			(pintype "passive+no_connect")
		)
		(pad "G14" smd circle
			(at 8.255 -1.905 90)
			(size 0.64 0.64)
			(layers "F.Cu" "F.Mask")
			(net 1 "GND")
			(pinfunction "GND")
			(pintype "passive")
		)
		(pad "G15" smd circle
			(at 6.985 -1.905 90)
			(size 0.64 0.64)
			(layers "F.Cu" "F.Mask")
			(net 188 "unconnected-(J18C-LA12_P-PadG15)")
			(pinfunction "LA12_P")
			(pintype "passive+no_connect")
		)
		(pad "G16" smd circle
			(at 5.714 -1.905 90)
			(size 0.64 0.64)
			(layers "F.Cu" "F.Mask")
			(net 189 "unconnected-(J18C-LA12_N-PadG16)")
			(pinfunction "LA12_N")
			(pintype "passive+no_connect")
		)
		(pad "G17" smd circle
			(at 4.445 -1.905 90)
			(size 0.64 0.64)
			(layers "F.Cu" "F.Mask")
			(net 1 "GND")
			(pinfunction "GND")
			(pintype "passive")
		)
		(pad "G18" smd circle
			(at 3.173 -1.905 90)
			(size 0.64 0.64)
			(layers "F.Cu" "F.Mask")
			(net 455 "/FMC+ HSPC/FMC.IO2_P")
			(pinfunction "LA16_P")
			(pintype "passive")
		)
		(pad "G19" smd circle
			(at 1.904 -1.905 90)
			(size 0.64 0.64)
			(layers "F.Cu" "F.Mask")
			(net 450 "/FMC+ HSPC/FMC.IO2_N")
			(pinfunction "LA16_N")
			(pintype "passive")
		)
		(pad "G20" smd circle
			(at 0.633 -1.905 90)
			(size 0.64 0.64)
			(layers "F.Cu" "F.Mask")
			(net 1 "GND")
			(pinfunction "GND")
			(pintype "passive")
		)
		(pad "G21" smd circle
			(at -0.635 -1.905 90)
			(size 0.64 0.64)
			(layers "F.Cu" "F.Mask")
			(net 418 "/FMC+ HSPC/FMC.IO1_P")
			(pinfunction "LA20_P")
			(pintype "passive")
		)
		(pad "G22" smd circle
			(at -1.905 -1.905 90)
			(size 0.64 0.64)
			(layers "F.Cu" "F.Mask")
			(net 414 "/FMC+ HSPC/FMC.IO1_N")
			(pinfunction "LA20_N")
			(pintype "passive")
		)
		(pad "G23" smd circle
			(at -3.176 -1.905 90)
			(size 0.64 0.64)
			(layers "F.Cu" "F.Mask")
			(net 1 "GND")
			(pinfunction "GND")
			(pintype "passive")
		)
		(pad "G24" smd circle
			(at -4.446 -1.905 90)
			(size 0.64 0.64)
			(layers "F.Cu" "F.Mask")
			(net 405 "/FMC+ HSPC/FMC.IO6_P")
			(pinfunction "LA22_P")
			(pintype "passive")
		)
		(pad "G25" smd circle
			(at -5.715 -1.905 90)
			(size 0.64 0.64)
			(layers "F.Cu" "F.Mask")
			(net 401 "/FMC+ HSPC/FMC.IO6_N")
			(pinfunction "LA22_N")
			(pintype "passive")
		)
		(pad "G26" smd circle
			(at -6.986 -1.905 90)
			(size 0.64 0.64)
			(layers "F.Cu" "F.Mask")
			(net 1 "GND")
			(pinfunction "GND")
			(pintype "passive")
		)
	)
)
